(kicad_pcb
	(version 20260206)
	(generator "pcbnew")
	(generator_version "10.0")
	(general
		(thickness 1.6)
		(legacy_teardrops no)
	)
	(paper "A4")
	(title_block
		(title "Bryce Canyon_R.DPB_16317-1_OCP.brd")
		(comment 1 "Bryce Canyon / footprints 58-65 of 2099")
	)
	(layers
		(0 "F.Cu" signal "TOP")
		(4 "In1.Cu" signal "L2GND")
		(6 "In2.Cu" signal "L3")
		(8 "In3.Cu" signal "L4VCC")
		(10 "In4.Cu" signal "L5VCC")
		(12 "In5.Cu" signal "L6")
		(14 "In6.Cu" signal "L7GND")
		(2 "B.Cu" signal "BOTTOM")
		(9 "F.Adhes" user "F.Adhesive")
		(11 "B.Adhes" user "B.Adhesive")
		(13 "F.Paste" user "Package Geometry/Pastemask Top")
		(15 "B.Paste" user "Package Geometry/Pastemask Bottom")
		(5 "F.SilkS" user "Ref Des/Silkscreen Top")
		(7 "B.SilkS" user "Ref Des/Silkscreen Bottom")
		(1 "F.Mask" user "Board Geometry/Soldermask Top")
		(3 "B.Mask" user "Board Geometry/Soldermask Bottom")
		(17 "Dwgs.User" user "User.Drawings")
		(19 "Cmts.User" user "User.Comments")
		(21 "Eco1.User" user "User.Eco1")
		(23 "Eco2.User" user "User.Eco2")
		(25 "Edge.Cuts" user "Board Geometry/Outline")
		(27 "Margin" user)
		(31 "F.CrtYd" user "Package Geometry/Place Bound Top")
		(29 "B.CrtYd" user "Package Geometry/Place Bound Bottom")
		(35 "F.Fab" user "Ref Des/Assembly Top")
		(33 "B.Fab" user "Ref Des/Assembly Bottom")
	)
	(footprint ""
		(layer "F.Cu")
		(at 176.6824 -9.9314 180)
		(property "Reference" "C416"
			(at 0 0 180)
			(layer "F.SilkS")
			(hide yes)
			(effects
				(font
					(size 1.27 1.27)
				)
			)
		)
		(property "Value" "SCD033U25V2KX-GP"
			(at 1.1811 -2.7051 180)
			(unlocked yes)
			(layer "F.Fab")
			(hide yes)
			(effects
				(font
					(size 1.016 1.016)
					(thickness 0.1524)
				)
			)
		)
		(property "Device Type" "C402H22"
			(at 1.1811 -4.2291 180)
			(unlocked yes)
			(layer "F.Fab")
			(hide yes)
			(effects
				(font
					(size 1.016 1.016)
					(thickness 0.1524)
				)
			)
		)
		(duplicate_pad_numbers_are_jumpers no)
		(fp_rect
			(start -0.4318 0.9525)
			(end 0.4318 -0.9525)
			(stroke
				(width 0)
				(type default)
			)
			(fill no)
			(layer "F.CrtYd")
		)
		(fp_rect
			(start -0.4318 0.9525)
			(end 0.4318 -0.9525)
			(stroke
				(width 0)
				(type default)
			)
			(fill no)
			(layer "F.Fab")
		)
		(pad "1" smd custom
			(at 0 -0.4445 180)
			(size 0.1524 0.1524)
			(layers "F.Cu" "F.Mask" "F.Paste")
			(net "P12V_B")
			(options
				(clearance outline)
				(anchor circle)
			)
			(primitives
				(gr_poly
					(pts
						(arc
							(start 0.3048 -0.2032)
							(mid 0.275042 -0.275042)
							(end 0.2032 -0.3048)
						)
						(arc
							(start -0.2032 -0.3048)
							(mid -0.275042 -0.275042)
							(end -0.3048 -0.2032)
						)
						(arc
							(start -0.3048 0.2032)
							(mid -0.275042 0.275042)
							(end -0.2032 0.3048)
						)
						(arc
							(start 0.2032 0.3048)
							(mid 0.275042 0.275042)
							(end 0.3048 0.2032)
						)
					)
					(width 0)
					(fill yes)
				)
			)
		)
		(pad "2" smd custom
			(at 0 0.4445 180)
			(size 0.1524 0.1524)
			(layers "F.Cu" "F.Mask" "F.Paste")
			(net "SW_HDD_N29")
			(options
				(clearance outline)
				(anchor circle)
			)
			(primitives
				(gr_poly
					(pts
						(arc
							(start 0.3048 -0.2032)
							(mid 0.275042 -0.275042)
							(end 0.2032 -0.3048)
						)
						(arc
							(start -0.2032 -0.3048)
							(mid -0.275042 -0.275042)
							(end -0.3048 -0.2032)
						)
						(arc
							(start -0.3048 0.2032)
							(mid -0.275042 0.275042)
							(end -0.2032 0.3048)
						)
						(arc
							(start 0.2032 0.3048)
							(mid 0.275042 0.275042)
							(end 0.3048 0.2032)
						)
					)
					(width 0)
					(fill yes)
				)
			)
		)
	)
	(footprint ""
		(layer "F.Cu")
		(at 282.619958 -104.894888)
		(property "Reference" "TC3"
			(at 0 0 0)
			(layer "F.SilkS")
			(hide yes)
			(effects
				(font
					(size 1.27 1.27)
				)
			)
		)
		(property "Value" "SE270U16VM-8-GP"
			(at -4.5974 -2.54 0)
			(unlocked yes)
			(layer "F.Fab")
			(hide yes)
			(effects
				(font
					(size 1.016 1.016)
					(thickness 0.1524)
				)
			)
		)
		(property "Device Type" "SE361416H394"
			(at -4.5974 -4.064 0)
			(unlocked yes)
			(layer "F.Fab")
			(hide yes)
			(effects
				(font
					(size 1.016 1.016)
					(thickness 0.1524)
				)
			)
		)
		(duplicate_pad_numbers_are_jumpers no)
		(fp_line
			(start -3.556 -3.4163)
			(end -2.3622 -4.6101)
			(stroke
				(width 0.1524)
				(type default)
			)
			(layer "F.SilkS")
		)
		(fp_line
			(start -3.556 4.6101)
			(end -3.556 -3.4163)
			(stroke
				(width 0.1524)
				(type default)
			)
			(layer "F.SilkS")
		)
		(fp_line
			(start -2.3622 -4.6101)
			(end 2.3622 -4.6101)
			(stroke
				(width 0.1524)
				(type default)
			)
			(layer "F.SilkS")
		)
		(fp_line
			(start 2.3622 -4.6101)
			(end 3.556 -3.4163)
			(stroke
				(width 0.1524)
				(type default)
			)
			(layer "F.SilkS")
		)
		(fp_line
			(start 3.556 -3.4163)
			(end 3.556 4.6101)
			(stroke
				(width 0.1524)
				(type default)
			)
			(layer "F.SilkS")
		)
		(fp_line
			(start 3.556 4.6101)
			(end -3.556 4.6101)
			(stroke
				(width 0.1524)
				(type default)
			)
			(layer "F.SilkS")
		)
		(fp_rect
			(start -3.302 3.6449)
			(end 3.302 -3.6449)
			(stroke
				(width 0)
				(type default)
			)
			(fill no)
			(layer "F.CrtYd")
		)
		(fp_poly
			(pts
				(xy 3.81 4.6863) (xy 3.81 -3.4925) (xy 3.302 -3.4925) (xy 3.302 3.6449) (xy -3.302 3.6449) (xy -3.302 -3.6449)
				(xy 3.302 -3.6449) (xy 3.302 -3.5052) (xy 3.81 -3.5052) (xy 3.81 -4.6863) (xy -3.81 -4.6863) (xy -3.81 4.6863)
			)
			(stroke
				(width 0)
				(type default)
			)
			(fill no)
			(layer "F.CrtYd")
		)
		(fp_rect
			(start -3.81 4.6863)
			(end 3.81 -4.6863)
			(stroke
				(width 0)
				(type default)
			)
			(fill no)
			(layer "F.Fab")
		)
		(pad "1" smd rect
			(at 0 -2.574036)
			(size 1.4224 3.556)
			(layers "F.Cu" "F.Mask" "F.Paste")
			(net "P12V_B")
		)
		(pad "2" smd rect
			(at 0 2.574036)
			(size 1.4224 3.556)
			(layers "F.Cu" "F.Mask" "F.Paste")
			(net "GND")
		)
	)
	(footprint ""
		(layer "F.Cu")
		(at 265.625072 -337.309206 90)
		(property "Reference" "R1054"
			(at 0 0 90)
			(layer "F.SilkS")
			(hide yes)
			(effects
				(font
					(size 1.27 1.27)
				)
			)
		)
		(property "Value" "10R5F-1-GP"
			(at 0 -8.9535 90)
			(unlocked yes)
			(layer "F.Fab")
			(hide yes)
			(effects
				(font
					(size 1.27 1.016)
					(thickness 0.1524)
				)
			)
		)
		(property "Device Type" "R805H24"
			(at 0 -10.6299 90)
			(unlocked yes)
			(layer "F.Fab")
			(hide yes)
			(effects
				(font
					(size 1.27 1.016)
					(thickness 0.1524)
				)
			)
		)
		(duplicate_pad_numbers_are_jumpers no)
		(fp_line
			(start 0.889 -1.7018)
			(end -0.889 -1.7018)
			(stroke
				(width 0.1524)
				(type default)
			)
			(layer "F.SilkS")
		)
		(fp_line
			(start 0.889 -1.7018)
			(end 0.889 -0.381)
			(stroke
				(width 0.1524)
				(type default)
			)
			(layer "F.SilkS")
		)
		(fp_line
			(start -0.889 -1.7018)
			(end -0.889 0.2794)
			(stroke
				(width 0.1524)
				(type default)
			)
			(layer "F.SilkS")
		)
		(fp_line
			(start -0.889 0.0762)
			(end -0.889 1.7018)
			(stroke
				(width 0.1524)
				(type default)
			)
			(layer "F.SilkS")
		)
		(fp_line
			(start 0.889 1.7018)
			(end 0.889 -0.508)
			(stroke
				(width 0.1524)
				(type default)
			)
			(layer "F.SilkS")
		)
		(fp_line
			(start -0.889 1.7018)
			(end 0.889 1.7018)
			(stroke
				(width 0.1524)
				(type default)
			)
			(layer "F.SilkS")
		)
		(fp_poly
			(pts
				(xy 0.9652 -1.778) (xy 0.9652 1.778) (xy -0.9652 1.778) (xy -0.9652 -1.778)
			)
			(stroke
				(width 0)
				(type default)
			)
			(fill no)
			(layer "F.CrtYd")
		)
		(fp_rect
			(start -0.9652 1.778)
			(end 0.9652 -1.778)
			(stroke
				(width 0)
				(type default)
			)
			(fill no)
			(layer "F.Fab")
		)
		(pad "1" smd rect
			(at 0 -0.9652 90)
			(size 1.397 1.143)
			(layers "F.Cu" "F.Mask" "F.Paste")
			(net "MB3_12V_CTRL_GATE3")
		)
		(pad "2" smd rect
			(at 0 0.9652 90)
			(size 1.397 1.143)
			(layers "F.Cu" "F.Mask" "F.Paste")
			(net "MB3_CM_GATE_R")
		)
	)
	(footprint ""
		(layer "F.Cu")
		(at 370.205 -258.826 90)
		(property "Reference" "C130"
			(at 0 0 90)
			(layer "F.SilkS")
			(hide yes)
			(effects
				(font
					(size 1.27 1.27)
				)
			)
		)
		(property "Value" "SCD033U25V2KX-GP"
			(at 1.1811 -2.7051 90)
			(unlocked yes)
			(layer "F.Fab")
			(hide yes)
			(effects
				(font
					(size 1.016 1.016)
					(thickness 0.1524)
				)
			)
		)
		(property "Device Type" "C402H22"
			(at 1.1811 -4.2291 90)
			(unlocked yes)
			(layer "F.Fab")
			(hide yes)
			(effects
				(font
					(size 1.016 1.016)
					(thickness 0.1524)
				)
			)
		)
		(duplicate_pad_numbers_are_jumpers no)
		(fp_rect
			(start -0.4318 0.9525)
			(end 0.4318 -0.9525)
			(stroke
				(width 0)
				(type default)
			)
			(fill no)
			(layer "F.CrtYd")
		)
		(fp_rect
			(start -0.4318 0.9525)
			(end 0.4318 -0.9525)
			(stroke
				(width 0)
				(type default)
			)
			(fill no)
			(layer "F.Fab")
		)
		(pad "1" smd custom
			(at 0 -0.4445 90)
			(size 0.1524 0.1524)
			(layers "F.Cu" "F.Mask" "F.Paste")
			(net "P12V_B")
			(options
				(clearance outline)
				(anchor circle)
			)
			(primitives
				(gr_poly
					(pts
						(arc
							(start 0.3048 -0.2032)
							(mid 0.275042 -0.275042)
							(end 0.2032 -0.3048)
						)
						(arc
							(start -0.2032 -0.3048)
							(mid -0.275042 -0.275042)
							(end -0.3048 -0.2032)
						)
						(arc
							(start -0.3048 0.2032)
							(mid -0.275042 0.275042)
							(end -0.2032 0.3048)
						)
						(arc
							(start 0.2032 0.3048)
							(mid 0.275042 0.275042)
							(end 0.3048 0.2032)
						)
					)
					(width 0)
					(fill yes)
				)
			)
		)
		(pad "2" smd custom
			(at 0 0.4445 90)
			(size 0.1524 0.1524)
			(layers "F.Cu" "F.Mask" "F.Paste")
			(net "SW_HDD_N7")
			(options
				(clearance outline)
				(anchor circle)
			)
			(primitives
				(gr_poly
					(pts
						(arc
							(start 0.3048 -0.2032)
							(mid 0.275042 -0.275042)
							(end 0.2032 -0.3048)
						)
						(arc
							(start -0.2032 -0.3048)
							(mid -0.275042 -0.275042)
							(end -0.3048 -0.2032)
						)
						(arc
							(start -0.3048 0.2032)
							(mid -0.275042 0.275042)
							(end -0.2032 0.3048)
						)
						(arc
							(start 0.2032 0.3048)
							(mid 0.275042 0.275042)
							(end 0.3048 0.2032)
						)
					)
					(width 0)
					(fill yes)
				)
			)
		)
	)
	(footprint ""
		(layer "F.Cu")
		(at 464.82 -142.875 -90)
		(property "Reference" "R591"
			(at 0 0 270)
			(layer "F.SilkS")
			(hide yes)
			(effects
				(font
					(size 1.27 1.27)
				)
			)
		)
		(property "Value" "300KR2F-GP"
			(at 0.064008 -3.993896 270)
			(unlocked yes)
			(layer "F.Fab")
			(hide yes)
			(effects
				(font
					(size 1.016 1.016)
					(thickness 0.1524)
				)
			)
		)
		(property "Device Type" "R402H16"
			(at 0.064008 -5.517896 270)
			(unlocked yes)
			(layer "F.Fab")
			(hide yes)
			(effects
				(font
					(size 1.016 1.016)
					(thickness 0.1524)
				)
			)
		)
		(duplicate_pad_numbers_are_jumpers no)
		(fp_line
			(start -0.508 -0.9398)
			(end -0.508 0.9398)
			(stroke
				(width 0.1524)
				(type default)
			)
			(layer "F.SilkS")
		)
		(fp_line
			(start 0.508 -0.9398)
			(end -0.508 -0.9398)
			(stroke
				(width 0.1524)
				(type default)
			)
			(layer "F.SilkS")
		)
		(fp_rect
			(start -0.508 0.9398)
			(end 0.508 -0.9398)
			(stroke
				(width 0)
				(type default)
			)
			(fill no)
			(layer "F.CrtYd")
		)
		(fp_rect
			(start -0.508 0.9398)
			(end 0.508 -0.9398)
			(stroke
				(width 0)
				(type default)
			)
			(fill no)
			(layer "F.Fab")
		)
		(pad "1" smd custom
			(at 0 -0.4445 270)
			(size 0.1397 0.1397)
			(layers "F.Cu" "F.Mask" "F.Paste")
			(net "SW_HDD_N22")
			(options
				(clearance outline)
				(anchor circle)
			)
			(primitives
				(gr_poly
					(pts
						(arc
							(start -0.1778 -0.2794)
							(mid -0.249642 -0.249642)
							(end -0.2794 -0.1778)
						)
						(arc
							(start -0.2794 0.1778)
							(mid -0.249642 0.249642)
							(end -0.1778 0.2794)
						)
						(arc
							(start 0.1778 0.2794)
							(mid 0.249642 0.249642)
							(end 0.2794 0.1778)
						)
						(arc
							(start 0.2794 -0.1778)
							(mid 0.249642 -0.249642)
							(end 0.1778 -0.2794)
						)
					)
					(width 0)
					(fill yes)
				)
			)
		)
		(pad "2" smd custom
			(at 0 0.4445 270)
			(size 0.1397 0.1397)
			(layers "F.Cu" "F.Mask" "F.Paste")
			(net "P12V_B")
			(options
				(clearance outline)
				(anchor circle)
			)
			(primitives
				(gr_poly
					(pts
						(arc
							(start -0.1778 -0.2794)
							(mid -0.249642 -0.249642)
							(end -0.2794 -0.1778)
						)
						(arc
							(start -0.2794 0.1778)
							(mid -0.249642 0.249642)
							(end -0.1778 0.2794)
						)
						(arc
							(start 0.1778 0.2794)
							(mid 0.249642 0.249642)
							(end 0.2794 0.1778)
						)
						(arc
							(start 0.2794 -0.1778)
							(mid 0.249642 -0.249642)
							(end 0.1778 -0.2794)
						)
					)
					(width 0)
					(fill yes)
				)
			)
		)
	)
	(footprint ""
		(layer "F.Cu")
		(at 16.891 -17.653 180)
		(property "Reference" "D24"
			(at 0 0 180)
			(layer "F.SilkS")
			(hide yes)
			(effects
				(font
					(size 1.27 1.27)
				)
			)
		)
		(property "Value" "RB551V30-GP"
			(at 0 -6.7818 180)
			(unlocked yes)
			(layer "F.Fab")
			(hide yes)
			(effects
				(font
					(size 1.016 1.016)
					(thickness 0.1524)
				)
			)
		)
		(property "Device Type" "SOD323AKH38"
			(at 0 -8.6868 180)
			(unlocked yes)
			(layer "F.Fab")
			(hide yes)
			(effects
				(font
					(size 1.016 1.016)
					(thickness 0.1524)
				)
			)
		)
		(duplicate_pad_numbers_are_jumpers no)
		(fp_line
			(start 0.889 2.159)
			(end -0.889 2.159)
			(stroke
				(width 0.1524)
				(type default)
			)
			(layer "F.SilkS")
		)
		(fp_line
			(start 0.889 -1.9304)
			(end 0.889 2.159)
			(stroke
				(width 0.1524)
				(type default)
			)
			(layer "F.SilkS")
		)
		(fp_line
			(start 0.762 2.0574)
			(end -0.762 2.0574)
			(stroke
				(width 0.508)
				(type default)
			)
			(layer "F.SilkS")
		)
		(fp_line
			(start -0.889 2.159)
			(end -0.889 -1.9304)
			(stroke
				(width 0.1524)
				(type default)
			)
			(layer "F.SilkS")
		)
		(fp_line
			(start -0.889 -1.9304)
			(end 0.889 -1.9304)
			(stroke
				(width 0.1524)
				(type default)
			)
			(layer "F.SilkS")
		)
		(fp_rect
			(start -1.016 2.3114)
			(end 1.016 -2.0066)
			(stroke
				(width 0)
				(type default)
			)
			(fill no)
			(layer "F.CrtYd")
		)
		(fp_poly
			(pts
				(xy -1.016 -2.0066) (xy 1.016 -2.0066) (xy 1.016 2.3114) (xy -1.016 2.3114)
			)
			(stroke
				(width 0)
				(type default)
			)
			(fill no)
			(layer "F.Fab")
		)
		(pad "A" smd rect
			(at 0 -1.143 180)
			(size 0.5588 1.016)
			(layers "F.Cu" "F.Mask" "F.Paste")
			(net "SW_HDD_R24")
		)
		(pad "K" smd rect
			(at 0 1.143 180)
			(size 0.5588 1.016)
			(layers "F.Cu" "F.Mask" "F.Paste")
			(net "SW_HDD_N24")
		)
	)
	(footprint ""
		(layer "F.Cu")
		(at 18.669 -214.249)
		(property "Reference" "R204"
			(at 0 0 0)
			(layer "F.SilkS")
			(hide yes)
			(effects
				(font
					(size 1.27 1.27)
				)
			)
		)
		(property "Value" "91R3F-1-GP"
			(at -0.0254 -2.5146 0)
			(unlocked yes)
			(layer "F.Fab")
			(hide yes)
			(effects
				(font
					(size 1.016 1.016)
					(thickness 0.1524)
				)
			)
		)
		(property "Device Type" "R603H22"
			(at -0.0254 -4.0386 0)
			(unlocked yes)
			(layer "F.Fab")
			(hide yes)
			(effects
				(font
					(size 1.016 1.016)
					(thickness 0.1524)
				)
			)
		)
		(duplicate_pad_numbers_are_jumpers no)
		(fp_line
			(start -0.4826 0)
			(end -0.2032 0)
			(stroke
				(width 0.2032)
				(type default)
			)
			(layer "F.SilkS")
		)
		(fp_line
			(start 0.2032 0)
			(end 0.4826 0)
			(stroke
				(width 0.2032)
				(type default)
			)
			(layer "F.SilkS")
		)
		(fp_rect
			(start -0.5842 1.3335)
			(end 0.5842 -1.3335)
			(stroke
				(width 0)
				(type default)
			)
			(fill no)
			(layer "F.CrtYd")
		)
		(fp_rect
			(start -0.5842 1.3335)
			(end 0.5842 -1.3335)
			(stroke
				(width 0)
				(type default)
			)
			(fill no)
			(layer "F.Fab")
		)
		(pad "1" smd custom
			(at 0 -0.762)
			(size 0.2159 0.2159)
			(layers "F.Cu" "F.Mask" "F.Paste")
			(net "P5V_B_1")
			(options
				(clearance outline)
				(anchor circle)
			)
			(primitives
				(gr_poly
					(pts
						(arc
							(start -0.3302 -0.4318)
							(mid -0.402042 -0.402042)
							(end -0.4318 -0.3302)
						)
						(arc
							(start -0.4318 0.3302)
							(mid -0.402042 0.402042)
							(end -0.3302 0.4318)
						)
						(arc
							(start 0.3302 0.4318)
							(mid 0.402042 0.402042)
							(end 0.4318 0.3302)
						)
						(arc
							(start 0.4318 -0.3302)
							(mid 0.402042 -0.402042)
							(end 0.3302 -0.4318)
						)
					)
					(width 0)
					(fill yes)
				)
			)
		)
		(pad "2" smd custom
			(at 0 0.762)
			(size 0.2159 0.2159)
			(layers "F.Cu" "F.Mask" "F.Paste")
			(net "DRV_ACT_0")
			(options
				(clearance outline)
				(anchor circle)
			)
			(primitives
				(gr_poly
					(pts
						(arc
							(start -0.3302 -0.4318)
							(mid -0.402042 -0.402042)
							(end -0.4318 -0.3302)
						)
						(arc
							(start -0.4318 0.3302)
							(mid -0.402042 0.402042)
							(end -0.3302 0.4318)
						)
						(arc
							(start 0.3302 0.4318)
							(mid 0.402042 0.402042)
							(end 0.4318 0.3302)
						)
						(arc
							(start 0.4318 -0.3302)
							(mid 0.402042 -0.402042)
							(end 0.3302 -0.4318)
						)
					)
					(width 0)
					(fill yes)
				)
			)
		)
	)
	(footprint ""
		(layer "F.Cu")
		(at 401.193 -250.444 90)
		(property "Reference" "R298"
			(at 0 0 90)
			(layer "F.SilkS")
			(hide yes)
			(effects
				(font
					(size 1.27 1.27)
				)
			)
		)
		(property "Value" "200KR2F-L-GP"
			(at 0.064008 -3.993896 90)
			(unlocked yes)
			(layer "F.Fab")
			(hide yes)
			(effects
				(font
					(size 1.016 1.016)
					(thickness 0.1524)
				)
			)
		)
		(property "Device Type" "R402H16"
			(at 0.064008 -5.517896 90)
			(unlocked yes)
			(layer "F.Fab")
			(hide yes)
			(effects
				(font
					(size 1.016 1.016)
					(thickness 0.1524)
				)
			)
		)
		(duplicate_pad_numbers_are_jumpers no)
		(fp_line
			(start 0.508 -0.9398)
			(end -0.508 -0.9398)
			(stroke
				(width 0.1524)
				(type default)
			)
			(layer "F.SilkS")
		)
		(fp_line
			(start -0.508 -0.9398)
			(end -0.508 0.9398)
			(stroke
				(width 0.1524)
				(type default)
			)
			(layer "F.SilkS")
		)
		(fp_rect
			(start -0.508 0.9398)
			(end 0.508 -0.9398)
			(stroke
				(width 0)
				(type default)
			)
			(fill no)
			(layer "F.CrtYd")
		)
		(fp_rect
			(start -0.508 0.9398)
			(end 0.508 -0.9398)
			(stroke
				(width 0)
				(type default)
			)
			(fill no)
			(layer "F.Fab")
		)
		(pad "1" smd custom
			(at 0 -0.4445 90)
			(size 0.1397 0.1397)
			(layers "F.Cu" "F.Mask" "F.Paste")
			(net "SW_HDD_R8")
			(options
				(clearance outline)
				(anchor circle)
			)
			(primitives
				(gr_poly
					(pts
						(arc
							(start -0.1778 -0.2794)
							(mid -0.249642 -0.249642)
							(end -0.2794 -0.1778)
						)
						(arc
							(start -0.2794 0.1778)
							(mid -0.249642 0.249642)
							(end -0.1778 0.2794)
						)
						(arc
							(start 0.1778 0.2794)
							(mid 0.249642 0.249642)
							(end 0.2794 0.1778)
						)
						(arc
							(start 0.2794 -0.1778)
							(mid 0.249642 -0.249642)
							(end 0.1778 -0.2794)
						)
					)
					(width 0)
					(fill yes)
				)
			)
		)
		(pad "2" smd custom
			(at 0 0.4445 90)
			(size 0.1397 0.1397)
			(layers "F.Cu" "F.Mask" "F.Paste")
			(net "SW_HDD_N8")
			(options
				(clearance outline)
				(anchor circle)
			)
			(primitives
				(gr_poly
					(pts
						(arc
							(start -0.1778 -0.2794)
							(mid -0.249642 -0.249642)
							(end -0.2794 -0.1778)
						)
						(arc
							(start -0.2794 0.1778)
							(mid -0.249642 0.249642)
							(end -0.1778 0.2794)
						)
						(arc
							(start 0.1778 0.2794)
							(mid 0.249642 0.249642)
							(end 0.2794 0.1778)
						)
						(arc
							(start 0.2794 -0.1778)
							(mid 0.249642 -0.249642)
							(end 0.1778 -0.2794)
						)
					)
					(width 0)
					(fill yes)
				)
			)
		)
	)
)
